(kicad_pcb
	(version 20260206)
	(generator "pcbnew")
	(generator_version "10.0")
	(general
		(thickness 1.6)
		(legacy_teardrops no)
	)
	(paper "A4")
	(title_block
		(title "v1-chassis-manager — T6M_CM_d_v01_1031_1645.brd")
		(comment 1 "Open CloudServer (Microsoft) / footprint 550 of 2512 (U14), pads 354-408 of 408")
	)
	(layers
		(0 "F.Cu" signal "TOP")
		(4 "In1.Cu" signal "GND1")
		(6 "In2.Cu" signal "IN1")
		(8 "In3.Cu" signal "VCC1")
		(10 "In4.Cu" signal "VCC2")
		(12 "In5.Cu" signal "GND2")
		(14 "In6.Cu" signal "IN2")
		(16 "In7.Cu" signal "IN3")
		(18 "In8.Cu" signal "GND3")
		(2 "B.Cu" signal "BOTTOM")
		(9 "F.Adhes" user "F.Adhesive")
		(11 "B.Adhes" user "B.Adhesive")
		(13 "F.Paste" user "Package Geometry/Pastemask Top")
		(15 "B.Paste" user "Package Geometry/Pastemask Bottom")
		(5 "F.SilkS" user "Ref Des/Silkscreen Top")
		(7 "B.SilkS" user "Ref Des/Silkscreen Bottom")
		(1 "F.Mask" user "Board Geometry/Soldermask Top")
		(3 "B.Mask" user "Board Geometry/Soldermask Bottom")
		(17 "Dwgs.User" user "User.Drawings")
		(19 "Cmts.User" user "User.Comments")
		(21 "Eco1.User" user "User.Eco1")
		(23 "Eco2.User" user "User.Eco2")
		(25 "Edge.Cuts" user "Board Geometry/Outline")
		(27 "Margin" user)
		(31 "F.CrtYd" user "Package Geometry/Place Bound Top")
		(29 "B.CrtYd" user "Package Geometry/Place Bound Bottom")
		(35 "F.Fab" user "Ref Des/Assembly Top")
		(33 "B.Fab" user "Ref Des/Assembly Bottom")
	)
	(footprint ""
		(layer "F.Cu")
		(at 65.741804 -134.859522 -90)
		(property "Reference" "U14"
			(at 12.258294 13.71092 90)
			(unlocked yes)
			(layer "F.SilkS")
			(effects
				(font
					(size 1.6002 1.1938)
					(thickness 0.1524)
				)
				(justify left)
			)
		)
		(property "Value" ""
			(at 0 0 270)
			(layer "F.Fab")
			(effects
				(font
					(size 1.27 1.27)
				)
			)
		)
		(duplicate_pad_numbers_are_jumpers no)
		(pad "V12" smd circle
			(at 0.40005 5.199888 270)
			(size 0.3683 0.3683)
			(layers "F.Cu" "F.Mask" "F.Paste")
			(net "BMC_NODE1_DDR_D1")
		)
		(pad "V13" smd circle
			(at 1.199896 5.199888 270)
			(size 0.3683 0.3683)
			(layers "F.Cu" "F.Mask" "F.Paste")
			(net "P0V75_BMC_VTTREF_NODE1")
		)
		(pad "V14" smd circle
			(at 1.999996 5.199888 270)
			(size 0.3683 0.3683)
			(layers "F.Cu" "F.Mask" "F.Paste")
			(net "BMC_NODE1_DDR_ODT")
		)
		(pad "V15" smd circle
			(at 2.800096 5.199888 270)
			(size 0.3683 0.3683)
			(layers "F.Cu" "F.Mask" "F.Paste")
			(net "BMC_NODE1_DDR_MA2")
		)
		(pad "V16" smd circle
			(at 3.599942 5.199888 270)
			(size 0.3683 0.3683)
			(layers "F.Cu" "F.Mask" "F.Paste")
			(net "BMC_NODE1_DDR_IOZ")
		)
		(pad "V17" smd circle
			(at 4.400042 5.199888 270)
			(size 0.3683 0.3683)
			(layers "F.Cu" "F.Mask" "F.Paste")
			(net "BMC_NODE1_HPLLAV33")
		)
		(pad "V18" smd circle
			(at 5.199888 5.199888 270)
			(size 0.3683 0.3683)
			(layers "F.Cu" "F.Mask" "F.Paste")
			(net "GND")
		)
		(pad "V19" smd circle
			(at 5.999988 5.199888 270)
			(size 0.3683 0.3683)
			(layers "F.Cu" "F.Mask" "F.Paste")
			(net "PECIVDD")
		)
		(pad "V20" smd circle
			(at 6.800088 5.199888 270)
			(size 0.3683 0.3683)
			(layers "F.Cu" "F.Mask" "F.Paste")
			(net "Net_527")
		)
		(pad "V21" smd circle
			(at 7.599934 5.199888 270)
			(size 0.3683 0.3683)
			(layers "F.Cu" "F.Mask" "F.Paste")
			(net "Net_523")
		)
		(pad "V22" smd circle
			(at 8.400034 5.199888 270)
			(size 0.3683 0.3683)
			(layers "F.Cu" "F.Mask" "F.Paste")
			(net "Net_518")
		)
		(pad "W1" smd circle
			(at -8.400034 5.999988 270)
			(size 0.3683 0.3683)
			(layers "F.Cu" "F.Mask" "F.Paste")
			(net "Net_470")
		)
		(pad "W2" smd circle
			(at -7.599934 5.999988 270)
			(size 0.3683 0.3683)
			(layers "F.Cu" "F.Mask" "F.Paste")
			(net "Net_481")
		)
		(pad "W3" smd circle
			(at -6.800088 5.999988 270)
			(size 0.3683 0.3683)
			(layers "F.Cu" "F.Mask" "F.Paste")
			(net "Net_1750")
		)
		(pad "W4" smd circle
			(at -5.999988 5.999988 270)
			(size 0.3683 0.3683)
			(layers "F.Cu" "F.Mask" "F.Paste")
			(net "Net_1772")
		)
		(pad "W5" smd circle
			(at -5.199888 5.999988 270)
			(size 0.3683 0.3683)
			(layers "F.Cu" "F.Mask" "F.Paste")
			(net "Net_1774")
		)
		(pad "W6" smd circle
			(at -4.400042 5.999988 270)
			(size 0.3683 0.3683)
			(layers "F.Cu" "F.Mask" "F.Paste")
			(net "Net_508")
		)
		(pad "W7" smd circle
			(at -3.599942 5.999988 270)
			(size 0.3683 0.3683)
			(layers "F.Cu" "F.Mask" "F.Paste")
			(net "Net_1784")
		)
		(pad "W8" smd circle
			(at -2.800096 5.999988 270)
			(size 0.3683 0.3683)
			(layers "F.Cu" "F.Mask" "F.Paste")
			(net "BMC_NODE1_DDR_D15")
		)
		(pad "W9" smd circle
			(at -1.999996 5.999988 270)
			(size 0.3683 0.3683)
			(layers "F.Cu" "F.Mask" "F.Paste")
			(net "BMC_NODE1_DDR_D12")
		)
		(pad "W10" smd circle
			(at -1.199896 5.999988 270)
			(size 0.3683 0.3683)
			(layers "F.Cu" "F.Mask" "F.Paste")
			(net "BMC_NODE1_DDR_DM0")
		)
		(pad "W11" smd circle
			(at -0.40005 5.999988 270)
			(size 0.3683 0.3683)
			(layers "F.Cu" "F.Mask" "F.Paste")
			(net "BMC_NODE1_DDR_D5")
		)
		(pad "W12" smd circle
			(at 0.40005 5.999988 270)
			(size 0.3683 0.3683)
			(layers "F.Cu" "F.Mask" "F.Paste")
			(net "BMC_NODE1_DDR_D0")
		)
		(pad "W13" smd circle
			(at 1.199896 5.999988 270)
			(size 0.3683 0.3683)
			(layers "F.Cu" "F.Mask" "F.Paste")
			(net "BMC_NODE1_DDR_RAS_L")
		)
		(pad "W14" smd circle
			(at 1.999996 5.999988 270)
			(size 0.3683 0.3683)
			(layers "F.Cu" "F.Mask" "F.Paste")
			(net "BMC_NODE1_DDR_BA0")
		)
		(pad "W15" smd circle
			(at 2.800096 5.999988 270)
			(size 0.3683 0.3683)
			(layers "F.Cu" "F.Mask" "F.Paste")
			(net "BMC_NODE1_DDR_MA1")
		)
		(pad "W16" smd circle
			(at 3.599942 5.999988 270)
			(size 0.3683 0.3683)
			(layers "F.Cu" "F.Mask" "F.Paste")
			(net "BMC_NODE1_DDR_MA5")
		)
		(pad "W17" smd circle
			(at 4.400042 5.999988 270)
			(size 0.3683 0.3683)
			(layers "F.Cu" "F.Mask" "F.Paste")
			(net "BMC_NODE1_DDR_MA12")
		)
		(pad "W18" smd circle
			(at 5.199888 5.999988 270)
			(size 0.3683 0.3683)
			(layers "F.Cu" "F.Mask" "F.Paste")
			(net "P3V3_NODE1")
		)
		(pad "W19" smd circle
			(at 5.999988 5.999988 270)
			(size 0.3683 0.3683)
			(layers "F.Cu" "F.Mask" "F.Paste")
			(net "BMC_NODE1_V1PLLAV12")
		)
		(pad "W20" smd circle
			(at 6.800088 5.999988 270)
			(size 0.3683 0.3683)
			(layers "F.Cu" "F.Mask" "F.Paste")
			(net "FM_BMC_NODE1_RESET_L")
		)
		(pad "W21" smd circle
			(at 7.599934 5.999988 270)
			(size 0.3683 0.3683)
			(layers "F.Cu" "F.Mask" "F.Paste")
			(net "Net_526")
		)
		(pad "W22" smd circle
			(at 8.400034 5.999988 270)
			(size 0.3683 0.3683)
			(layers "F.Cu" "F.Mask" "F.Paste")
			(net "Net_522")
		)
		(pad "Y1" smd circle
			(at -8.400034 6.800088 270)
			(size 0.3683 0.3683)
			(layers "F.Cu" "F.Mask" "F.Paste")
			(net "Net_482")
		)
		(pad "Y2" smd circle
			(at -7.599934 6.800088 270)
			(size 0.3683 0.3683)
			(layers "F.Cu" "F.Mask" "F.Paste")
			(net "Net_474")
		)
		(pad "Y3" smd circle
			(at -6.800088 6.800088 270)
			(size 0.3683 0.3683)
			(layers "F.Cu" "F.Mask" "F.Paste")
			(net "Net_1773")
		)
		(pad "Y4" smd circle
			(at -5.999988 6.800088 270)
			(size 0.3683 0.3683)
			(layers "F.Cu" "F.Mask" "F.Paste")
			(net "Net_1775")
		)
		(pad "Y5" smd circle
			(at -5.199888 6.800088 270)
			(size 0.3683 0.3683)
			(layers "F.Cu" "F.Mask" "F.Paste")
			(net "Net_1778")
		)
		(pad "Y6" smd circle
			(at -4.400042 6.800088 270)
			(size 0.3683 0.3683)
			(layers "F.Cu" "F.Mask" "F.Paste")
			(net "Net_1782")
		)
		(pad "Y7" smd circle
			(at -3.599942 6.800088 270)
			(size 0.3683 0.3683)
			(layers "F.Cu" "F.Mask" "F.Paste")
			(net "Net_506")
		)
		(pad "Y8" smd circle
			(at -2.800096 6.800088 270)
			(size 0.3683 0.3683)
			(layers "F.Cu" "F.Mask" "F.Paste")
			(net "BMC_NODE1_DDR_D14")
		)
		(pad "Y9" smd circle
			(at -1.999996 6.800088 270)
			(size 0.3683 0.3683)
			(layers "F.Cu" "F.Mask" "F.Paste")
			(net "BMC_NODE1_DDR_D11")
		)
		(pad "Y10" smd circle
			(at -1.199896 6.800088 270)
			(size 0.3683 0.3683)
			(layers "F.Cu" "F.Mask" "F.Paste")
			(net "BMC_NODE1_DDR_D7")
		)
		(pad "Y11" smd circle
			(at -0.40005 6.800088 270)
			(size 0.3683 0.3683)
			(layers "F.Cu" "F.Mask" "F.Paste")
			(net "BMC_NODE1_DDR_D4")
		)
		(pad "Y12" smd circle
			(at 0.40005 6.800088 270)
			(size 0.3683 0.3683)
			(layers "F.Cu" "F.Mask" "F.Paste")
			(net "BMC_NODE1_DDR_CKE")
		)
		(pad "Y13" smd circle
			(at 1.199896 6.800088 270)
			(size 0.3683 0.3683)
			(layers "F.Cu" "F.Mask" "F.Paste")
			(net "BMC_NODE1_DDR_WE_L")
		)
		(pad "Y14" smd circle
			(at 1.999996 6.800088 270)
			(size 0.3683 0.3683)
			(layers "F.Cu" "F.Mask" "F.Paste")
			(net "BMC_NODE1_DDR_BA2")
		)
		(pad "Y15" smd circle
			(at 2.800096 6.800088 270)
			(size 0.3683 0.3683)
			(layers "F.Cu" "F.Mask" "F.Paste")
			(net "BMC_NODE1_DDR_MA10")
		)
		(pad "Y16" smd circle
			(at 3.599942 6.800088 270)
			(size 0.3683 0.3683)
			(layers "F.Cu" "F.Mask" "F.Paste")
			(net "BMC_NODE1_DDR_MA3")
		)
		(pad "Y17" smd circle
			(at 4.400042 6.800088 270)
			(size 0.3683 0.3683)
			(layers "F.Cu" "F.Mask" "F.Paste")
			(net "BMC_NODE1_DDR_MA13")
		)
		(pad "Y18" smd circle
			(at 5.199888 6.800088 270)
			(size 0.3683 0.3683)
			(layers "F.Cu" "F.Mask" "F.Paste")
			(net "P1V26_BMC_NODE1")
		)
		(pad "Y19" smd circle
			(at 5.999988 6.800088 270)
			(size 0.3683 0.3683)
			(layers "F.Cu" "F.Mask" "F.Paste")
			(net "GND")
		)
		(pad "Y20" smd circle
			(at 6.800088 6.800088 270)
			(size 0.3683 0.3683)
			(layers "F.Cu" "F.Mask" "F.Paste")
			(net "BMC_NODE1_V1PLLAV12")
		)
		(pad "Y21" smd circle
			(at 7.599934 6.800088 270)
			(size 0.3683 0.3683)
			(layers "F.Cu" "F.Mask" "F.Paste")
			(net "Net_1769")
		)
		(pad "Y22" smd circle
			(at 8.400034 6.800088 270)
			(size 0.3683 0.3683)
			(layers "F.Cu" "F.Mask" "F.Paste")
			(net "Net_525")
		)
	)
)
